# S9S_MB_2U (Grand Teton) — schematic netlist excerpt (pin names and nets, part order shuffled) for the footprints in the layout excerpt that follows; sources: Cadence DE-HDL packaged netlist, KiCad conversion of 03242023_DA0F0TMBIJ0_F0T_Motherboard_J_brd_V01_OCP.brd

C392  Q_CAP  47UF 4V 20% X6S  pkg C0805  page 76 : A = PVCCIN_CPU0 ; B = GND
R3  Q_RES  33.2 1% CHIP  pkg 0402LF  page 13 : A = PECI_CPU_GTL ; B = PECI_CPU0_GTL_R
R60  Q_RES  200 1% CHIP  pkg 0402LF  page 45 : A = SVID_ALERT1_CPU1_N ; B = SVID_ALERT1_CPU1_R_N

(kicad_pcb
	(version 20260206)
	(generator "pcbnew")
	(generator_version "10.0")
	(general
		(thickness 1.6)
		(legacy_teardrops no)
	)
	(paper "A4")
	(title_block
		(title "03242023_DA0F0TMBIJ0_F0T_Motherboard_J_brd_V01_OCP.brd")
		(comment 1 "Grand Teton / footprints 4435-4437 of 6105")
	)
	(layers
		(0 "F.Cu" signal "TOP")
		(4 "In1.Cu" signal "GND")
		(6 "In2.Cu" signal "IN1")
		(8 "In3.Cu" signal "GND1")
		(10 "In4.Cu" signal "IN2")
		(12 "In5.Cu" signal "GND2")
		(14 "In6.Cu" signal "IN3")
		(16 "In7.Cu" signal "GND3")
		(18 "In8.Cu" signal "VCC")
		(20 "In9.Cu" signal "VCC1")
		(22 "In10.Cu" signal "GND4")
		(24 "In11.Cu" signal "IN4")
		(26 "In12.Cu" signal "GND5")
		(28 "In13.Cu" signal "IN5")
		(30 "In14.Cu" signal "GND6")
		(32 "In15.Cu" signal "IN6")
		(34 "In16.Cu" signal "GND7")
		(2 "B.Cu" signal "BOTTOM")
		(9 "F.Adhes" user "F.Adhesive")
		(11 "B.Adhes" user "B.Adhesive")
		(13 "F.Paste" user "Package Geometry/Pastemask Top")
		(15 "B.Paste" user "Package Geometry/Pastemask Bottom")
		(5 "F.SilkS" user "Ref Des/Silkscreen Top")
		(7 "B.SilkS" user "Ref Des/Silkscreen Bottom")
		(1 "F.Mask" user "Board Geometry/Soldermask Top")
		(3 "B.Mask" user "Board Geometry/Soldermask Bottom")
		(17 "Dwgs.User" user "User.Drawings")
		(19 "Cmts.User" user "User.Comments")
		(21 "Eco1.User" user "User.Eco1")
		(23 "Eco2.User" user "User.Eco2")
		(25 "Edge.Cuts" user "Board Geometry/Outline")
		(27 "Margin" user)
		(31 "F.CrtYd" user "Package Geometry/Place Bound Top")
		(29 "B.CrtYd" user "Package Geometry/Place Bound Bottom")
		(35 "F.Fab" user "Ref Des/Assembly Top")
		(33 "B.Fab" user "Ref Des/Assembly Bottom")
	)
	(footprint ""
		(layer "B.Cu")
		(at 72.401684 -188.458856 90)
		(property "Reference" "R60"
			(at 0 0 90)
			(layer "B.SilkS")
			(hide yes)
			(effects
				(font
					(size 1.27 1.27)
				)
				(justify mirror)
			)
		)
		(property "Value" ""
			(at 0 0 90)
			(layer "B.Fab")
			(effects
				(font
					(size 1.27 1.27)
				)
				(justify mirror)
			)
		)
		(duplicate_pad_numbers_are_jumpers no)
		(fp_line
			(start 0.7874 -0.4064)
			(end -0.7874 -0.4064)
			(stroke
				(width 0.1524)
				(type default)
			)
			(layer "B.SilkS")
		)
		(fp_line
			(start -0.7874 -0.4064)
			(end -0.7874 0.4064)
			(stroke
				(width 0.1524)
				(type default)
			)
			(layer "B.SilkS")
		)
		(fp_line
			(start 0.7874 0.4064)
			(end 0.7874 -0.4064)
			(stroke
				(width 0.1524)
				(type default)
			)
			(layer "B.SilkS")
		)
		(fp_line
			(start -0.7874 0.4064)
			(end 0.7874 0.4064)
			(stroke
				(width 0.1524)
				(type default)
			)
			(layer "B.SilkS")
		)
		(fp_line
			(start 0.67945 -0.305054)
			(end 0.12065 -0.305054)
			(stroke
				(width 0.1)
				(type default)
			)
			(layer "B.Fab")
		)
		(fp_line
			(start 0.12065 -0.305054)
			(end 0.12065 -0.2794)
			(stroke
				(width 0.1)
				(type default)
			)
			(layer "B.Fab")
		)
		(fp_line
			(start -0.12065 -0.3048)
			(end -0.67945 -0.3048)
			(stroke
				(width 0.1)
				(type default)
			)
			(layer "B.Fab")
		)
		(fp_line
			(start -0.67945 -0.3048)
			(end -0.67945 0.3048)
			(stroke
				(width 0.1)
				(type default)
			)
			(layer "B.Fab")
		)
		(fp_line
			(start 0.12065 -0.2794)
			(end -0.12065 -0.2794)
			(stroke
				(width 0.1)
				(type default)
			)
			(layer "B.Fab")
		)
		(fp_line
			(start -0.12065 -0.2794)
			(end -0.12065 -0.3048)
			(stroke
				(width 0.1)
				(type default)
			)
			(layer "B.Fab")
		)
		(fp_line
			(start 0.12065 0.2794)
			(end 0.12065 0.3048)
			(stroke
				(width 0.1)
				(type default)
			)
			(layer "B.Fab")
		)
		(fp_line
			(start -0.120396 0.2794)
			(end 0.12065 0.2794)
			(stroke
				(width 0.1)
				(type default)
			)
			(layer "B.Fab")
		)
		(fp_line
			(start 0.67945 0.3048)
			(end 0.67945 -0.305054)
			(stroke
				(width 0.1)
				(type default)
			)
			(layer "B.Fab")
		)
		(fp_line
			(start 0.12065 0.3048)
			(end 0.67945 0.3048)
			(stroke
				(width 0.1)
				(type default)
			)
			(layer "B.Fab")
		)
		(fp_line
			(start -0.120396 0.3048)
			(end -0.120396 0.2794)
			(stroke
				(width 0.1)
				(type default)
			)
			(layer "B.Fab")
		)
		(fp_line
			(start -0.67945 0.3048)
			(end -0.120396 0.3048)
			(stroke
				(width 0.1)
				(type default)
			)
			(layer "B.Fab")
		)
		(pad "1" smd circle
			(at 0.40005 0 270)
			(size 0 0)
			(layers "B.Cu" "B.Mask" "B.Paste")
			(net "SVID_ALERT1_CPU1_N")
		)
		(pad "2" smd circle
			(at -0.40005 0 270)
			(size 0 0)
			(layers "B.Cu" "B.Mask" "B.Paste")
			(net "SVID_ALERT1_CPU1_R_N")
		)
	)
	(footprint ""
		(layer "B.Cu")
		(at 359.960418 -296.054526)
		(property "Reference" "C392"
			(at 0 0 0)
			(layer "B.SilkS")
			(hide yes)
			(effects
				(font
					(size 1.27 1.27)
				)
				(justify mirror)
			)
		)
		(property "Value" ""
			(at 0 0 0)
			(layer "B.Fab")
			(effects
				(font
					(size 1.27 1.27)
				)
				(justify mirror)
			)
		)
		(duplicate_pad_numbers_are_jumpers no)
		(fp_line
			(start -1.524 -0.762)
			(end -1.524 0.762)
			(stroke
				(width 0.1524)
				(type default)
			)
			(layer "B.SilkS")
		)
		(fp_line
			(start -1.524 0.762)
			(end 1.524 0.762)
			(stroke
				(width 0.1524)
				(type default)
			)
			(layer "B.SilkS")
		)
		(fp_line
			(start 1.524 -0.762)
			(end -1.524 -0.762)
			(stroke
				(width 0.1524)
				(type default)
			)
			(layer "B.SilkS")
		)
		(fp_line
			(start 1.524 0.762)
			(end 1.524 -0.762)
			(stroke
				(width 0.1524)
				(type default)
			)
			(layer "B.SilkS")
		)
		(fp_line
			(start -1.1049 -0.724916)
			(end 1.1049 -0.724916)
			(stroke
				(width 0.1)
				(type default)
			)
			(layer "B.Fab")
		)
		(fp_line
			(start -1.1049 0.724916)
			(end -1.1049 -0.724916)
			(stroke
				(width 0.1)
				(type default)
			)
			(layer "B.Fab")
		)
		(fp_line
			(start 1.1049 -0.724916)
			(end 1.1049 0.724916)
			(stroke
				(width 0.1)
				(type default)
			)
			(layer "B.Fab")
		)
		(fp_line
			(start 1.1049 0.724916)
			(end -1.1049 0.724916)
			(stroke
				(width 0.1)
				(type default)
			)
			(layer "B.Fab")
		)
		(pad "1" smd rect
			(at 0.889 0)
			(size 1.016 1.27)
			(layers "B.Cu" "B.Mask" "B.Paste")
			(net "PVCCIN_CPU0")
		)
		(pad "2" smd rect
			(at -0.889 0)
			(size 1.016 1.27)
			(layers "B.Cu" "B.Mask" "B.Paste")
			(net "GND")
		)
	)
	(footprint ""
		(layer "B.Cu")
		(at 310.567578 -193.52895 -90)
		(property "Reference" "R3"
			(at 0 0 90)
			(layer "B.SilkS")
			(hide yes)
			(effects
				(font
					(size 1.27 1.27)
				)
				(justify mirror)
			)
		)
		(property "Value" ""
			(at 0 0 90)
			(layer "B.Fab")
			(effects
				(font
					(size 1.27 1.27)
				)
				(justify mirror)
			)
		)
		(duplicate_pad_numbers_are_jumpers no)
		(fp_line
			(start -0.7874 0.4064)
			(end 0.7874 0.4064)
			(stroke
				(width 0.1524)
				(type default)
			)
			(layer "B.SilkS")
		)
		(fp_line
			(start 0.7874 0.4064)
			(end 0.7874 -0.4064)
			(stroke
				(width 0.1524)
				(type default)
			)
			(layer "B.SilkS")
		)
		(fp_line
			(start -0.7874 -0.4064)
			(end -0.7874 0.4064)
			(stroke
				(width 0.1524)
				(type default)
			)
			(layer "B.SilkS")
		)
		(fp_line
			(start 0.7874 -0.4064)
			(end -0.7874 -0.4064)
			(stroke
				(width 0.1524)
				(type default)
			)
			(layer "B.SilkS")
		)
		(fp_line
			(start -0.67945 0.3048)
			(end -0.120396 0.3048)
			(stroke
				(width 0.1)
				(type default)
			)
			(layer "B.Fab")
		)
		(fp_line
			(start -0.120396 0.3048)
			(end -0.120396 0.2794)
			(stroke
				(width 0.1)
				(type default)
			)
			(layer "B.Fab")
		)
		(fp_line
			(start 0.12065 0.3048)
			(end 0.67945 0.3048)
			(stroke
				(width 0.1)
				(type default)
			)
			(layer "B.Fab")
		)
		(fp_line
			(start 0.67945 0.3048)
			(end 0.67945 -0.305054)
			(stroke
				(width 0.1)
				(type default)
			)
			(layer "B.Fab")
		)
		(fp_line
			(start -0.120396 0.2794)
			(end 0.12065 0.2794)
			(stroke
				(width 0.1)
				(type default)
			)
			(layer "B.Fab")
		)
		(fp_line
			(start 0.12065 0.2794)
			(end 0.12065 0.3048)
			(stroke
				(width 0.1)
				(type default)
			)
			(layer "B.Fab")
		)
		(fp_line
			(start -0.12065 -0.2794)
			(end -0.12065 -0.3048)
			(stroke
				(width 0.1)
				(type default)
			)
			(layer "B.Fab")
		)
		(fp_line
			(start 0.12065 -0.2794)
			(end -0.12065 -0.2794)
			(stroke
				(width 0.1)
				(type default)
			)
			(layer "B.Fab")
		)
		(fp_line
			(start -0.67945 -0.3048)
			(end -0.67945 0.3048)
			(stroke
				(width 0.1)
				(type default)
			)
			(layer "B.Fab")
		)
		(fp_line
			(start -0.12065 -0.3048)
			(end -0.67945 -0.3048)
			(stroke
				(width 0.1)
				(type default)
			)
			(layer "B.Fab")
		)
		(fp_line
			(start 0.12065 -0.305054)
			(end 0.12065 -0.2794)
			(stroke
				(width 0.1)
				(type default)
			)
			(layer "B.Fab")
		)
		(fp_line
			(start 0.67945 -0.305054)
			(end 0.12065 -0.305054)
			(stroke
				(width 0.1)
				(type default)
			)
			(layer "B.Fab")
		)
		(pad "1" smd circle
			(at 0.40005 0 90)
			(size 0 0)
			(layers "B.Cu" "B.Mask" "B.Paste")
			(net "PECI_CPU_GTL")
		)
		(pad "2" smd circle
			(at -0.40005 0 90)
			(size 0 0)
			(layers "B.Cu" "B.Mask" "B.Paste")
			(net "PECI_CPU0_GTL_R")
		)
	)
)
